FILE_TYPE = MACRO_DRAWING;
SET COLOR_WIRE YELLOW;
SET COLOR_PROP ORANGE;
SET COLOR_DOT WHITE;
SET COLOR_ARC YELLOW;
SET COLOR_BODY GREEN;
SET COLOR_NOTE PURPLE;
SET PROP_DISPLAY VALUE;
SET PAGE_NUMBER P207;
FORCEADD QUANTA_TITLE_BLOCK_C..1
(4700 -1775);
FORCEPROP 1 LAST CUSTOM_TXT_CDS <NAME_2>
J 0
(1525 -1725);
FORCEPROP 1 LAST CUSTOM_TXT_CDS <NAME_1>
J 0
(1525 -1600);
FORCEPROP 1 LAST CUSTOM_TXT_CDS <Q_NUMBER>
J 0
(3297 -1672);
DISPLAY 1.212766 (3297 -1672);
FORCEPROP 1 LAST CUSTOM_TXT_CDS <Q_PROJ>
J 0
(2318 -1673);
DISPLAY 1.212766 (2318 -1673);
FORCEPROP 1 LAST CUSTOM_TXT_CDS <Q_REV>
J 0
(4516 -1672);
DISPLAY 1.212766 (4516 -1672);
FORCEPROP 1 LAST CUSTOM_TXT_CDS <CON_LAST_MODIFIED>
J 0
(2815 -1760);
DISPLAY 0.978723 (2815 -1760);
FORCEPROP 1 LAST CUSTOM_TXT_CDS <CON_PAGE_NUM> OF <CON_TOTAL_PAGES>
J 0
(4254 -1757);
DISPLAY 0.978723 (4254 -1757);
FORCEPROP 1 LAST Q_DEPT BU9
J 1
(937 -1726);
DISPLAY 1.957447 (937 -1726);
PAINT GREEN (937 -1726);
FORCEPROP 1 LAST Q_TITLE eFUSE - E1S_4
J 0
(-4600 -1725);
DISPLAY 2.446809 (-4600 -1725);
PAINT GREEN (-4600 -1725);
FORCEPROP 1 LAST COMMENT_BODY TRUE
J 0
(4712 -1788);
DISPLAY 0.978723 (4712 -1788);
PAINT GREEN (4712 -1788);
DISPLAY INVISIBLE (4712 -1788);
FORCEPROP 1 LAST CDS_LMAN_SYM_OUTLINE -9475,6775,100,-125
J 0
(4700 -1775);
DISPLAY 0.468085 (4700 -1775);
PAINT GREEN (4700 -1775);
DISPLAY INVISIBLE (4700 -1775);
FORCEPROP 2 LAST CDS_LIB pure_quanta
J 0
(4700 -1775);
DISPLAY INVISIBLE (4700 -1775);
FORCEPROP 2 LAST PAGE_BORDER TRUE
J 0
(-3190 3475);
DISPLAY 0.638298 (-3190 3475);
PAINT PINK (-3190 3475);
DISPLAY INVISIBLE (-3190 3475);
FORCEPROP 2 LAST CDS_XR_PAGE_TITLE CR-208 : @T6G_MB_LIB.T6G(SCH_1):PAGE208
J 0
(-3190 3475);
DISPLAY 0.638298 (-3190 3475);
PAINT PINK (-3190 3475);
DISPLAY INVISIBLE (-3190 3475);
FORCEPROP 2 LAST CUSTOM_TXT_CDS <XR_PAGE_TITLE>
J 0
(-3190 3475);
DISPLAY 0.638298 (-3190 3475);
PAINT PINK (-3190 3475);
DISPLAY INVISIBLE (-3190 3475);
FORCEPROP 0 LAST CDS_CON_LAST_MODIFIED Wed Mar 09 21:45:12 2022
J 0
(2815 -1760);
DISPLAY INVISIBLE (2815 -1760);
QUIT
